(kicad_pcb
	(version 20241229)
	(generator "pcbnew")
	(generator_version "9.0")
	(general
		(thickness 1.294)
		(legacy_teardrops no)
	)
	(paper "A3")
	(title_block
		(title "Kintex 410T devboard")
		(date "2024-04-03")
		(rev "1.1.2")
		(comment 9 "footprints 413-418 of 975")
	)
	(layers
		(0 "F.Cu" mixed)
		(4 "In1.Cu" power)
		(6 "In2.Cu" power)
		(8 "In3.Cu" mixed)
		(10 "In4.Cu" power)
		(12 "In5.Cu" mixed)
		(14 "In6.Cu" power)
		(16 "In7.Cu" mixed)
		(18 "In8.Cu" power)
		(2 "B.Cu" mixed)
		(9 "F.Adhes" user "F.Adhesive")
		(11 "B.Adhes" user "B.Adhesive")
		(13 "F.Paste" user)
		(15 "B.Paste" user)
		(5 "F.SilkS" user "F.Silkscreen")
		(7 "B.SilkS" user "B.Silkscreen")
		(1 "F.Mask" user)
		(3 "B.Mask" user)
		(17 "Dwgs.User" user "User.Drawings")
		(19 "Cmts.User" user "User.Comments")
		(21 "Eco1.User" user "User.Eco1")
		(23 "Eco2.User" user "User.Eco2")
		(25 "Edge.Cuts" user)
		(27 "Margin" user)
		(31 "F.CrtYd" user "F.Courtyard")
		(29 "B.CrtYd" user "B.Courtyard")
		(35 "F.Fab" user)
		(33 "B.Fab" user)
	)
	(footprint "antmicro-footprints:R_0402_1005Metric"
		(layer "F.Cu")
		(at 244.15 104.3)
		(descr "Resistor SMD 0402")
		(tags "resistor SMD 0402")
		(property "Reference" "R254"
			(at 0.8 0.35 0)
			(layer "F.SilkS")
			(effects
				(font
					(size 0.7 0.7)
					(thickness 0.15)
				)
				(justify left bottom)
			)
		)
		(property "Value" "R_0R_0402"
			(at 0 1.4 0)
			(layer "F.Fab")
			(effects
				(font
					(size 0.7 0.7)
					(thickness 0.15)
				)
				(justify left bottom)
			)
		)
		(property "Description" "SMD Chip Resistor, Jumper, 0 ohm, 100 mW, 0402 [1005 Metric], Thick Film, General Purpose"
			(at 0 0 0)
			(layer "F.Fab")
			(hide yes)
			(effects
				(font
					(size 1.27 1.27)
					(thickness 0.15)
				)
			)
		)
		(property "Author" "Antmicro"
			(at 0 0 0)
			(layer "F.Fab")
			(hide yes)
			(effects
				(font
					(size 1 1)
					(thickness 0.15)
				)
			)
		)
		(property "Current" "1A"
			(at 0 0 0)
			(layer "F.Fab")
			(hide yes)
			(effects
				(font
					(size 1 1)
					(thickness 0.15)
				)
			)
		)
		(property "License" "Apache-2.0"
			(at 0 0 0)
			(layer "F.Fab")
			(hide yes)
			(effects
				(font
					(size 1 1)
					(thickness 0.15)
				)
			)
		)
		(property "MPN" "ERJ2GE0R00X"
			(at 0 0 0)
			(layer "F.Fab")
			(hide yes)
			(effects
				(font
					(size 1 1)
					(thickness 0.15)
				)
			)
		)
		(property "Manufacturer" "Panasonic"
			(at 0 0 0)
			(layer "F.Fab")
			(hide yes)
			(effects
				(font
					(size 1 1)
					(thickness 0.15)
				)
			)
		)
		(property "Tolerance" ""
			(at 0 0 0)
			(layer "F.Fab")
			(hide yes)
			(effects
				(font
					(size 1 1)
					(thickness 0.15)
				)
			)
		)
		(property "Val" "0R"
			(at 0 0 0)
			(layer "F.Fab")
			(hide yes)
			(effects
				(font
					(size 1 1)
					(thickness 0.15)
				)
			)
		)
		(sheetname "HDMI + Ethernet")
		(sheetfile "hdmi-ethernet.kicad_sch")
		(attr smd)
		(fp_rect
			(start -0.925 -0.47)
			(end 0.925 0.47)
			(stroke
				(width 0.05)
				(type default)
			)
			(fill no)
			(layer "F.CrtYd")
		)
		(fp_rect
			(start -0.5 -0.25)
			(end 0.5 0.25)
			(stroke
				(width 0.15)
				(type solid)
			)
			(fill no)
			(layer "F.Fab")
		)
		(pad "1" smd roundrect
			(at -0.48 0)
			(size 0.59 0.64)
			(layers "F.Cu" "F.Mask" "F.Paste")
			(roundrect_rratio 0.25)
			(net 524 "/FPGA Bank 16 & 17/HDMI.D2_P")
			(pintype "passive")
		)
		(pad "2" smd roundrect
			(at 0.48 0)
			(size 0.59 0.64)
			(layers "F.Cu" "F.Mask" "F.Paste")
			(roundrect_rratio 0.25)
			(net 867 "/HDMI + Ethernet/HDMI_CONN_D2_P")
			(pintype "passive")
		)
	)
	(footprint "antmicro-footprints:R_0402_1005Metric"
		(layer "F.Cu")
		(at 218.4 149.8)
		(descr "Resistor SMD 0402")
		(tags "resistor SMD 0402")
		(property "Reference" "R197"
			(at -3.6 0.35 0)
			(layer "F.SilkS")
			(effects
				(font
					(size 0.7 0.7)
					(thickness 0.15)
				)
				(justify left bottom)
			)
		)
		(property "Value" "R_10k_0402"
			(at 0 1.4 0)
			(layer "F.Fab")
			(effects
				(font
					(size 0.7 0.7)
					(thickness 0.15)
				)
				(justify left bottom)
			)
		)
		(property "Description" "SMD Chip Resistor, 10 kohm, ± 1%, 62.5 mW, 0402 [1005 Metric], Thick Film, General Purpose"
			(at 0 0 0)
			(layer "F.Fab")
			(hide yes)
			(effects
				(font
					(size 1.27 1.27)
					(thickness 0.15)
				)
			)
		)
		(property "Author" "Antmicro"
			(at 0 0 0)
			(layer "F.Fab")
			(hide yes)
			(effects
				(font
					(size 1 1)
					(thickness 0.15)
				)
			)
		)
		(property "License" "Apache-2.0"
			(at 0 0 0)
			(layer "F.Fab")
			(hide yes)
			(effects
				(font
					(size 1 1)
					(thickness 0.15)
				)
			)
		)
		(property "MPN" "CR0402-FX-1002GLF"
			(at 0 0 0)
			(layer "F.Fab")
			(hide yes)
			(effects
				(font
					(size 1 1)
					(thickness 0.15)
				)
			)
		)
		(property "Manufacturer" "Bourns"
			(at 0 0 0)
			(layer "F.Fab")
			(hide yes)
			(effects
				(font
					(size 1 1)
					(thickness 0.15)
				)
			)
		)
		(property "Tolerance" "1%"
			(at 0 0 0)
			(layer "F.Fab")
			(hide yes)
			(effects
				(font
					(size 1 1)
					(thickness 0.15)
				)
			)
		)
		(property "Val" "10k"
			(at 0 0 0)
			(layer "F.Fab")
			(hide yes)
			(effects
				(font
					(size 1 1)
					(thickness 0.15)
				)
			)
		)
		(sheetname "HDMI + Ethernet")
		(sheetfile "hdmi-ethernet.kicad_sch")
		(attr smd)
		(fp_rect
			(start -0.925 -0.47)
			(end 0.925 0.47)
			(stroke
				(width 0.05)
				(type default)
			)
			(fill no)
			(layer "F.CrtYd")
		)
		(fp_rect
			(start -0.5 -0.25)
			(end 0.5 0.25)
			(stroke
				(width 0.15)
				(type solid)
			)
			(fill no)
			(layer "F.Fab")
		)
		(pad "1" smd roundrect
			(at -0.48 0)
			(size 0.59 0.64)
			(layers "F.Cu" "F.Mask" "F.Paste")
			(roundrect_rratio 0.25)
			(net 26 "+1V8")
			(pintype "passive")
		)
		(pad "2" smd roundrect
			(at 0.48 0)
			(size 0.59 0.64)
			(layers "F.Cu" "F.Mask" "F.Paste")
			(roundrect_rratio 0.25)
			(net 501 "/FPGA Bank 18 & 32/ETH_RMII.~{RESET}")
			(pintype "passive")
		)
	)
	(footprint "antmicro-footprints:C_0603_1608Metric"
		(layer "F.Cu")
		(at 177.5 165.5)
		(descr "Capacitor SMD 0603")
		(tags "capacitor 0603")
		(property "Reference" "C325"
			(at 1 0.4 0)
			(layer "F.SilkS")
			(effects
				(font
					(size 0.7 0.7)
					(thickness 0.15)
				)
				(justify left bottom)
			)
		)
		(property "Value" "C_22u_0603"
			(at 0 1.6 0)
			(layer "F.Fab")
			(effects
				(font
					(size 0.7 0.7)
					(thickness 0.15)
				)
				(justify left bottom)
			)
		)
		(property "Description" "SMD Multilayer Ceramic Capacitor, 22 µF, 6.3 V, 0603 [1608 Metric], ± 20%, X5R, GRM Series"
			(at 0 0 0)
			(layer "F.Fab")
			(hide yes)
			(effects
				(font
					(size 1.27 1.27)
					(thickness 0.15)
				)
			)
		)
		(property "Author" "Antmicro"
			(at 0 0 0)
			(layer "F.Fab")
			(hide yes)
			(effects
				(font
					(size 1 1)
					(thickness 0.15)
				)
			)
		)
		(property "Dielectric" ""
			(at 0 0 0)
			(layer "F.Fab")
			(hide yes)
			(effects
				(font
					(size 1 1)
					(thickness 0.15)
				)
			)
		)
		(property "License" "Apache-2.0"
			(at 0 0 0)
			(layer "F.Fab")
			(hide yes)
			(effects
				(font
					(size 1 1)
					(thickness 0.15)
				)
			)
		)
		(property "MPN" "GRM188R60J226MEA0D"
			(at 0 0 0)
			(layer "F.Fab")
			(hide yes)
			(effects
				(font
					(size 1 1)
					(thickness 0.15)
				)
			)
		)
		(property "Manufacturer" "Murata"
			(at 0 0 0)
			(layer "F.Fab")
			(hide yes)
			(effects
				(font
					(size 1 1)
					(thickness 0.15)
				)
			)
		)
		(property "Val" "22u"
			(at 0 0 0)
			(layer "F.Fab")
			(hide yes)
			(effects
				(font
					(size 1 1)
					(thickness 0.15)
				)
			)
		)
		(property "Voltage" ""
			(at 0 0 0)
			(layer "F.Fab")
			(hide yes)
			(effects
				(font
					(size 1 1)
					(thickness 0.15)
				)
			)
		)
		(sheetname "DC-DC Converters")
		(sheetfile "dc-dc.kicad_sch")
		(attr smd)
		(fp_line
			(start -0.15 -0.4)
			(end 0.15 -0.4)
			(stroke
				(width 0.15)
				(type solid)
			)
			(layer "F.SilkS")
		)
		(fp_line
			(start -0.15 0.4)
			(end 0.15 0.4)
			(stroke
				(width 0.15)
				(type solid)
			)
			(layer "F.SilkS")
		)
		(fp_rect
			(start -1.25 -0.65)
			(end 1.25 0.65)
			(stroke
				(width 0.05)
				(type solid)
			)
			(fill no)
			(layer "F.CrtYd")
		)
		(fp_rect
			(start -0.8 -0.4)
			(end 0.8 0.4)
			(stroke
				(width 0.15)
				(type solid)
			)
			(fill no)
			(layer "F.Fab")
		)
		(pad "1" smd roundrect
			(at -0.7 0)
			(size 0.8 1)
			(layers "F.Cu" "F.Mask" "F.Paste")
			(roundrect_rratio 0.2)
			(net 1 "GND")
			(pintype "passive")
		)
		(pad "2" smd roundrect
			(at 0.7 0)
			(size 0.8 1)
			(layers "F.Cu" "F.Mask" "F.Paste")
			(roundrect_rratio 0.2)
			(net 736 "/DC-DC Converters/3V3_local_2")
			(pintype "passive")
		)
	)
	(footprint "antmicro-footprints:R_0402_1005Metric"
		(layer "F.Cu")
		(at 209.86 81.74)
		(descr "Resistor SMD 0402")
		(tags "resistor SMD 0402")
		(property "Reference" "R6"
			(at -0.16 1.26 0)
			(layer "F.SilkS")
			(effects
				(font
					(size 0.7 0.7)
					(thickness 0.15)
				)
				(justify left bottom)
			)
		)
		(property "Value" "R_10k_0402"
			(at 0 1.4 0)
			(layer "F.Fab")
			(effects
				(font
					(size 0.7 0.7)
					(thickness 0.15)
				)
				(justify left bottom)
			)
		)
		(property "Description" "SMD Chip Resistor, 10 kohm, ± 1%, 62.5 mW, 0402 [1005 Metric], Thick Film, General Purpose"
			(at 0 0 0)
			(layer "F.Fab")
			(hide yes)
			(effects
				(font
					(size 1.27 1.27)
					(thickness 0.15)
				)
			)
		)
		(property "Author" "Antmicro"
			(at 0 0 0)
			(layer "F.Fab")
			(hide yes)
			(effects
				(font
					(size 1 1)
					(thickness 0.15)
				)
			)
		)
		(property "License" "Apache-2.0"
			(at 0 0 0)
			(layer "F.Fab")
			(hide yes)
			(effects
				(font
					(size 1 1)
					(thickness 0.15)
				)
			)
		)
		(property "MPN" "CR0402-FX-1002GLF"
			(at 0 0 0)
			(layer "F.Fab")
			(hide yes)
			(effects
				(font
					(size 1 1)
					(thickness 0.15)
				)
			)
		)
		(property "Manufacturer" "Bourns"
			(at 0 0 0)
			(layer "F.Fab")
			(hide yes)
			(effects
				(font
					(size 1 1)
					(thickness 0.15)
				)
			)
		)
		(property "Tolerance" "1%"
			(at 0 0 0)
			(layer "F.Fab")
			(hide yes)
			(effects
				(font
					(size 1 1)
					(thickness 0.15)
				)
			)
		)
		(property "Val" "10k"
			(at 0 0 0)
			(layer "F.Fab")
			(hide yes)
			(effects
				(font
					(size 1 1)
					(thickness 0.15)
				)
			)
		)
		(sheetname "FPGA Config")
		(sheetfile "fpga-config.kicad_sch")
		(attr smd)
		(fp_rect
			(start -0.925 -0.47)
			(end 0.925 0.47)
			(stroke
				(width 0.05)
				(type default)
			)
			(fill no)
			(layer "F.CrtYd")
		)
		(fp_rect
			(start -0.5 -0.25)
			(end 0.5 0.25)
			(stroke
				(width 0.15)
				(type solid)
			)
			(fill no)
			(layer "F.Fab")
		)
		(pad "1" smd roundrect
			(at -0.48 0)
			(size 0.59 0.64)
			(layers "F.Cu" "F.Mask" "F.Paste")
			(roundrect_rratio 0.25)
			(net 257 "/FPGA Config/INIT_B")
			(pintype "passive")
		)
		(pad "2" smd roundrect
			(at 0.48 0)
			(size 0.59 0.64)
			(layers "F.Cu" "F.Mask" "F.Paste")
			(roundrect_rratio 0.25)
			(net 24 "+3V3")
			(pintype "passive")
		)
	)
	(footprint "antmicro-footprints:C_Pol_EIA-B"
		(layer "F.Cu")
		(at 206.161 149.4)
		(property "Reference" "C1"
			(at -0.891 -1.69 0)
			(layer "F.SilkS")
			(effects
				(font
					(size 0.7 0.7)
					(thickness 0.15)
				)
				(justify left bottom)
			)
		)
		(property "Value" "C_Pol_330u_6.3V_KEMET-T520-B"
			(at -2.34 2.45 0)
			(layer "F.Fab")
			(effects
				(font
					(size 0.7 0.7)
					(thickness 0.15)
				)
				(justify left bottom)
			)
		)
		(property "Description" "Tantalum Polymer Capacitor, KO-CAP®, 330 µF, ± 20%, 6.3 V, B, 0.04 ohm, 1411 [3528 Metric]"
			(at 0 0 0)
			(layer "F.Fab")
			(hide yes)
			(effects
				(font
					(size 1.27 1.27)
					(thickness 0.15)
				)
			)
		)
		(property "Author" "Antmicro"
			(at 0 0 0)
			(layer "F.Fab")
			(hide yes)
			(effects
				(font
					(size 1 1)
					(thickness 0.15)
				)
			)
		)
		(property "Dielectric" ""
			(at 0 0 0)
			(layer "F.Fab")
			(hide yes)
			(effects
				(font
					(size 1 1)
					(thickness 0.15)
				)
			)
		)
		(property "License" "Apache-2.0"
			(at 0 0 0)
			(layer "F.Fab")
			(hide yes)
			(effects
				(font
					(size 1 1)
					(thickness 0.15)
				)
			)
		)
		(property "MPN" "T520B337M006ATE040"
			(at 0 0 0)
			(layer "F.Fab")
			(hide yes)
			(effects
				(font
					(size 1 1)
					(thickness 0.15)
				)
			)
		)
		(property "Manufacturer" "KEMET"
			(at 0 0 0)
			(layer "F.Fab")
			(hide yes)
			(effects
				(font
					(size 1 1)
					(thickness 0.15)
				)
			)
		)
		(property "Val" "330u"
			(at 0 0 0)
			(layer "F.Fab")
			(hide yes)
			(effects
				(font
					(size 1 1)
					(thickness 0.15)
				)
			)
		)
		(property "Voltage" "6.3V"
			(at 0 0 0)
			(layer "F.Fab")
			(hide yes)
			(effects
				(font
					(size 1 1)
					(thickness 0.15)
				)
			)
		)
		(sheetname "FPGA supply")
		(sheetfile "fpga-supply.kicad_sch")
		(attr smd)
		(fp_line
			(start -2.521 -1.676)
			(end -2.123 -1.676)
			(stroke
				(width 0.15)
				(type solid)
			)
			(layer "F.SilkS")
		)
		(fp_line
			(start -2.325 -1.475)
			(end -2.325 -1.878)
			(stroke
				(width 0.15)
				(type solid)
			)
			(layer "F.SilkS")
		)
		(fp_line
			(start -1.8 -1.6)
			(end 1.8 -1.6)
			(stroke
				(width 0.15)
				(type solid)
			)
			(layer "F.SilkS")
		)
		(fp_line
			(start -1.8 -1.3)
			(end -1.8 -1.6)
			(stroke
				(width 0.15)
				(type solid)
			)
			(layer "F.SilkS")
		)
		(fp_line
			(start -1.8 1.3)
			(end -1.8 1.6)
			(stroke
				(width 0.15)
				(type solid)
			)
			(layer "F.SilkS")
		)
		(fp_line
			(start 1.8 -1.3)
			(end 1.8 -1.6)
			(stroke
				(width 0.15)
				(type solid)
			)
			(layer "F.SilkS")
		)
		(fp_line
			(start 1.8 1.3)
			(end 1.8 1.6)
			(stroke
				(width 0.15)
				(type solid)
			)
			(layer "F.SilkS")
		)
		(fp_line
			(start 1.8 1.6)
			(end -1.8 1.6)
			(stroke
				(width 0.15)
				(type solid)
			)
			(layer "F.SilkS")
		)
		(fp_line
			(start -2.411 -1.35)
			(end -2.41 1.35)
			(stroke
				(width 0.05)
				(type solid)
			)
			(layer "F.CrtYd")
		)
		(fp_line
			(start -1.97 -1.75)
			(end -1.97 -1.35)
			(stroke
				(width 0.05)
				(type solid)
			)
			(layer "F.CrtYd")
		)
		(fp_line
			(start -1.97 -1.35)
			(end -2.41 -1.35)
			(stroke
				(width 0.05)
				(type solid)
			)
			(layer "F.CrtYd")
		)
		(fp_line
			(start -1.97 1.35)
			(end -2.41 1.35)
			(stroke
				(width 0.05)
				(type solid)
			)
			(layer "F.CrtYd")
		)
		(fp_line
			(start -1.97 1.35)
			(end -1.97 1.75)
			(stroke
				(width 0.05)
				(type solid)
			)
			(layer "F.CrtYd")
		)
		(fp_line
			(start 1.959 -1.75)
			(end -1.971 -1.75)
			(stroke
				(width 0.05)
				(type solid)
			)
			(layer "F.CrtYd")
		)
		(fp_line
			(start 1.959 -1.75)
			(end 1.959 -1.35)
			(stroke
				(width 0.05)
				(type solid)
			)
			(layer "F.CrtYd")
		)
		(fp_line
			(start 1.96 1.35)
			(end 1.96 1.75)
			(stroke
				(width 0.05)
				(type solid)
			)
			(layer "F.CrtYd")
		)
		(fp_line
			(start 1.96 1.75)
			(end -1.97 1.75)
			(stroke
				(width 0.05)
				(type solid)
			)
			(layer "F.CrtYd")
		)
		(fp_line
			(start 2.399 -1.35)
			(end 1.959 -1.35)
			(stroke
				(width 0.05)
				(type solid)
			)
			(layer "F.CrtYd")
		)
		(fp_line
			(start 2.399 -1.35)
			(end 2.4 1.35)
			(stroke
				(width 0.05)
				(type solid)
			)
			(layer "F.CrtYd")
		)
		(fp_line
			(start 2.4 1.35)
			(end 1.96 1.35)
			(stroke
				(width 0.05)
				(type solid)
			)
			(layer "F.CrtYd")
		)
		(fp_line
			(start -1.7 1.324)
			(end -1.551 1.475)
			(stroke
				(width 0.15)
				(type solid)
			)
			(layer "F.Fab")
		)
		(fp_rect
			(start -1.72 -1.5)
			(end 1.719 1.499)
			(stroke
				(width 0.15)
				(type solid)
			)
			(fill no)
			(layer "F.Fab")
		)
		(pad "1" smd roundrect
			(at -1.551 0)
			(size 1.2 2.2)
			(layers "F.Cu" "F.Mask" "F.Paste")
			(roundrect_rratio 0.1)
			(net 650 "+1V0")
			(pintype "passive")
		)
		(pad "2" smd roundrect
			(at 1.55 0)
			(size 1.2 2.2)
			(layers "F.Cu" "F.Mask" "F.Paste")
			(roundrect_rratio 0.1)
			(net 1 "GND")
			(pintype "passive")
		)
	)
	(footprint "antmicro-footprints:R_0402_1005Metric"
		(layer "F.Cu")
		(at 206.69 75.44 -90)
		(descr "Resistor SMD 0402")
		(tags "resistor SMD 0402")
		(property "Reference" "R9"
			(at -0.74 -0.41 270)
			(layer "F.SilkS")
			(effects
				(font
					(size 0.7 0.7)
					(thickness 0.15)
				)
				(justify left bottom)
			)
		)
		(property "Value" "R_330R_0402"
			(at 0 1.4 270)
			(layer "F.Fab")
			(effects
				(font
					(size 0.7 0.7)
					(thickness 0.15)
				)
				(justify left bottom)
			)
		)
		(property "Description" "SMD Chip Resistor, 330 ohm, ± 1%, 62.5 mW, 0402 [1005 Metric], Thick Film, General Purpose"
			(at 0 0 270)
			(layer "F.Fab")
			(hide yes)
			(effects
				(font
					(size 1.27 1.27)
					(thickness 0.15)
				)
			)
		)
		(property "Author" "Antmicro"
			(at 131.25 282.13 0)
			(layer "F.Fab")
			(hide yes)
			(effects
				(font
					(size 1 1)
					(thickness 0.15)
				)
			)
		)
		(property "License" "Apache-2.0"
			(at 131.25 282.13 0)
			(layer "F.Fab")
			(hide yes)
			(effects
				(font
					(size 1 1)
					(thickness 0.15)
				)
			)
		)
		(property "MPN" "CR0402-FX-3300GLF"
			(at 131.25 282.13 0)
			(layer "F.Fab")
			(hide yes)
			(effects
				(font
					(size 1 1)
					(thickness 0.15)
				)
			)
		)
		(property "Manufacturer" "Bourns"
			(at 131.25 282.13 0)
			(layer "F.Fab")
			(hide yes)
			(effects
				(font
					(size 1 1)
					(thickness 0.15)
				)
			)
		)
		(property "Tolerance" "1%"
			(at 131.25 282.13 0)
			(layer "F.Fab")
			(hide yes)
			(effects
				(font
					(size 1 1)
					(thickness 0.15)
				)
			)
		)
		(property "Val" "330R"
			(at 131.25 282.13 0)
			(layer "F.Fab")
			(hide yes)
			(effects
				(font
					(size 1 1)
					(thickness 0.15)
				)
			)
		)
		(sheetname "FPGA Config")
		(sheetfile "fpga-config.kicad_sch")
		(attr smd)
		(fp_rect
			(start -0.925 -0.47)
			(end 0.925 0.47)
			(stroke
				(width 0.05)
				(type default)
			)
			(fill no)
			(layer "F.CrtYd")
		)
		(fp_rect
			(start -0.5 -0.25)
			(end 0.5 0.25)
			(stroke
				(width 0.15)
				(type solid)
			)
			(fill no)
			(layer "F.Fab")
		)
		(pad "1" smd roundrect
			(at -0.48 0 270)
			(size 0.59 0.64)
			(layers "F.Cu" "F.Mask" "F.Paste")
			(roundrect_rratio 0.25)
			(net 17 "Net-(D1-C)")
			(pintype "passive")
		)
		(pad "2" smd roundrect
			(at 0.48 0 270)
			(size 0.59 0.64)
			(layers "F.Cu" "F.Mask" "F.Paste")
			(roundrect_rratio 0.25)
			(net 333 "Net-(Q1-D)")
			(pintype "passive")
		)
	)
)
